(kicad_pcb
	(version 20241229)
	(generator "pcbnew")
	(generator_version "9.0")
	(general
		(thickness 1.711)
		(legacy_teardrops no)
	)
	(paper "A4")
	(title_block
		(title "Antmicro Baseboard for Jetson AGX Thor")
		(date "2026-02-18")
		(rev "1.1.0")
		(company "Antmicro Ltd")
		(comment 1 "www.antmicro.com")
		(comment 9 "footprints 1132-1136 of 1170")
	)
	(layers
		(0 "F.Cu" signal)
		(4 "In1.Cu" signal)
		(6 "In2.Cu" signal)
		(8 "In3.Cu" signal)
		(10 "In4.Cu" jumper)
		(12 "In5.Cu" signal)
		(14 "In6.Cu" signal)
		(16 "In7.Cu" signal)
		(18 "In8.Cu" signal)
		(2 "B.Cu" signal)
		(9 "F.Adhes" user "F.Adhesive")
		(11 "B.Adhes" user "B.Adhesive")
		(13 "F.Paste" user)
		(15 "B.Paste" user)
		(5 "F.SilkS" user "F.Silkscreen")
		(7 "B.SilkS" user "B.Silkscreen")
		(1 "F.Mask" user)
		(3 "B.Mask" user)
		(17 "Dwgs.User" user "User.Drawings")
		(19 "Cmts.User" user "User.Comments")
		(21 "Eco1.User" user "User.Eco1")
		(23 "Eco2.User" user "User.Eco2")
		(25 "Edge.Cuts" user)
		(27 "Margin" user)
		(31 "F.CrtYd" user "F.Courtyard")
		(29 "B.CrtYd" user "B.Courtyard")
		(35 "F.Fab" user)
		(33 "B.Fab" user)
	)
	(footprint "antmicro-footprints:C_0402_1005Metric"
		(layer "B.Cu")
		(at 213.8 95.4 90)
		(descr "Capacitor SMD 0402")
		(tags "capacitor SMD 0402")
		(property "Reference" "C323"
			(at -3.7 -0.4 90)
			(layer "B.SilkS")
			(effects
				(font
					(size 0.7 0.7)
					(thickness 0.15)
				)
				(justify right top mirror)
			)
		)
		(property "Value" "C_100n_0402"
			(at -1.022927 -2.155213 90)
			(layer "B.Fab")
			(effects
				(font
					(size 0.7 0.7)
					(thickness 0.15)
				)
				(justify right top mirror)
			)
		)
		(property "Datasheet" "https://www.murata.com/products/productdetail?partno=GRM155R61H104KE14%23"
			(at 0 0 90)
			(layer "B.Fab")
			(hide yes)
			(effects
				(font
					(size 1.27 1.27)
					(thickness 0.15)
				)
				(justify mirror)
			)
		)
		(property "Description" "SMD Multilayer Ceramic Capacitor, 0.1 µF, 50 V, 0402 [1005 Metric], ± 10%, X5R, GRM Series"
			(at 0 0 90)
			(layer "B.Fab")
			(hide yes)
			(effects
				(font
					(size 1.27 1.27)
					(thickness 0.15)
				)
				(justify mirror)
			)
		)
		(property "Manufacturer" "Murata"
			(at 0 0 270)
			(unlocked yes)
			(layer "B.Fab")
			(hide yes)
			(effects
				(font
					(size 1 1)
					(thickness 0.15)
				)
				(justify mirror)
			)
		)
		(property "MPN" "GRM155R61H104KE14D"
			(at 0 0 270)
			(unlocked yes)
			(layer "B.Fab")
			(hide yes)
			(effects
				(font
					(size 1 1)
					(thickness 0.15)
				)
				(justify mirror)
			)
		)
		(property "Val" "100n"
			(at 0 0 270)
			(unlocked yes)
			(layer "B.Fab")
			(hide yes)
			(effects
				(font
					(size 1 1)
					(thickness 0.15)
				)
				(justify mirror)
			)
		)
		(property "License" "Apache-2.0"
			(at 0 0 270)
			(unlocked yes)
			(layer "B.Fab")
			(hide yes)
			(effects
				(font
					(size 1 1)
					(thickness 0.15)
				)
				(justify mirror)
			)
		)
		(property "Author" "Antmicro"
			(at 0 0 270)
			(unlocked yes)
			(layer "B.Fab")
			(hide yes)
			(effects
				(font
					(size 1 1)
					(thickness 0.15)
				)
				(justify mirror)
			)
		)
		(property "Voltage" "50V"
			(at 0 0 270)
			(unlocked yes)
			(layer "B.Fab")
			(hide yes)
			(effects
				(font
					(size 1 1)
					(thickness 0.15)
				)
				(justify mirror)
			)
		)
		(property "Dielectric" "X5R"
			(at 0 0 270)
			(unlocked yes)
			(layer "B.Fab")
			(hide yes)
			(effects
				(font
					(size 1 1)
					(thickness 0.15)
				)
				(justify mirror)
			)
		)
		(sheetname "/SoM_IO2/")
		(sheetfile "som_io2.kicad_sch")
		(attr smd)
		(fp_rect
			(start -0.925 0.47)
			(end 0.925 -0.47)
			(stroke
				(width 0.05)
				(type default)
			)
			(fill no)
			(layer "B.CrtYd")
		)
		(fp_line
			(start 0.504 -0.248)
			(end -0.494 -0.248)
			(stroke
				(width 0.15)
				(type solid)
			)
			(layer "B.Fab")
		)
		(fp_line
			(start -0.494 -0.248)
			(end -0.494 0.25)
			(stroke
				(width 0.15)
				(type solid)
			)
			(layer "B.Fab")
		)
		(fp_line
			(start 0.504 0.25)
			(end 0.504 -0.248)
			(stroke
				(width 0.15)
				(type solid)
			)
			(layer "B.Fab")
		)
		(fp_line
			(start -0.494 0.25)
			(end 0.504 0.25)
			(stroke
				(width 0.15)
				(type solid)
			)
			(layer "B.Fab")
		)
		(fp_text user "License: Apache-2.0"
			(at -0.939 -5.799 90)
			(layer "B.Fab")
			(effects
				(font
					(size 0.7 0.7)
					(thickness 0.15)
				)
				(justify right top mirror)
			)
		)
		(fp_text user "Author: Antmicro"
			(at -0.939 -3.399 90)
			(layer "B.Fab")
			(effects
				(font
					(size 0.7 0.7)
					(thickness 0.15)
				)
				(justify right top mirror)
			)
		)
		(fp_text user "${REFERENCE}"
			(at -0.939 -4.599 90)
			(layer "B.Fab")
			(effects
				(font
					(size 0.7 0.7)
					(thickness 0.15)
				)
				(justify right top mirror)
			)
		)
		(pad "1" smd roundrect
			(at -0.48 0 90)
			(size 0.59 0.64)
			(layers "B.Cu" "B.Mask" "B.Paste")
			(roundrect_rratio 0.25)
			(net 1112 "/SoM_IO2/DP0.AUX_C-")
			(pintype "passive")
		)
		(pad "2" smd roundrect
			(at 0.48 0 90)
			(size 0.59 0.64)
			(layers "B.Cu" "B.Mask" "B.Paste")
			(roundrect_rratio 0.25)
			(net 607 "/SoM_IO2/DP0.AUX-")
			(pintype "passive")
		)
	)
	(footprint "antmicro-footprints:R_0402_1005Metric"
		(layer "B.Cu")
		(at 103.46 66.01)
		(descr "Resistor SMD 0402")
		(tags "resistor SMD 0402")
		(property "Reference" "R4"
			(at -0.89 0.6 0)
			(layer "B.SilkS")
			(effects
				(font
					(size 0.7 0.7)
					(thickness 0.15)
				)
				(justify right top mirror)
			)
		)
		(property "Value" "R_49R9_0402"
			(at -1.011843 -1.772047 0)
			(layer "B.Fab")
			(effects
				(font
					(size 0.7 0.7)
					(thickness 0.15)
				)
				(justify right top mirror)
			)
		)
		(property "Datasheet" "https://www.bourns.com/docs/product-datasheets/cr.pdf"
			(at 0 0 0)
			(layer "B.Fab")
			(hide yes)
			(effects
				(font
					(size 1.27 1.27)
					(thickness 0.15)
				)
				(justify mirror)
			)
		)
		(property "Description" "SMD Chip Resistor, 49.9 ohm, ± 1%, 62.5 mW, 0402 [1005 Metric], Thick Film, General Purpose"
			(at 0 0 0)
			(layer "B.Fab")
			(hide yes)
			(effects
				(font
					(size 1.27 1.27)
					(thickness 0.15)
				)
				(justify mirror)
			)
		)
		(property "MPN" "CR0402-FX-49R9GLF"
			(at 0 0 180)
			(unlocked yes)
			(layer "B.Fab")
			(hide yes)
			(effects
				(font
					(size 1 1)
					(thickness 0.15)
				)
				(justify mirror)
			)
		)
		(property "Manufacturer" "Bourns"
			(at 0 0 180)
			(unlocked yes)
			(layer "B.Fab")
			(hide yes)
			(effects
				(font
					(size 1 1)
					(thickness 0.15)
				)
				(justify mirror)
			)
		)
		(property "License" "Apache-2.0"
			(at 0 0 180)
			(unlocked yes)
			(layer "B.Fab")
			(hide yes)
			(effects
				(font
					(size 1 1)
					(thickness 0.15)
				)
				(justify mirror)
			)
		)
		(property "Author" "Antmicro"
			(at 0 0 180)
			(unlocked yes)
			(layer "B.Fab")
			(hide yes)
			(effects
				(font
					(size 1 1)
					(thickness 0.15)
				)
				(justify mirror)
			)
		)
		(property "Val" "49R9"
			(at 0 0 180)
			(unlocked yes)
			(layer "B.Fab")
			(hide yes)
			(effects
				(font
					(size 1 1)
					(thickness 0.15)
				)
				(justify mirror)
			)
		)
		(property "Tolerance" "1%"
			(at 0 0 180)
			(unlocked yes)
			(layer "B.Fab")
			(hide yes)
			(effects
				(font
					(size 1 1)
					(thickness 0.15)
				)
				(justify mirror)
			)
		)
		(sheetname "/SoM_IO2/")
		(sheetfile "som_io2.kicad_sch")
		(attr smd)
		(fp_rect
			(start -0.925 0.47)
			(end 0.925 -0.47)
			(stroke
				(width 0.05)
				(type default)
			)
			(fill no)
			(layer "B.CrtYd")
		)
		(fp_rect
			(start -0.5 0.25)
			(end 0.5 -0.25)
			(stroke
				(width 0.15)
				(type solid)
			)
			(fill no)
			(layer "B.Fab")
		)
		(fp_text user "${REFERENCE}"
			(at -0.95 -3.168 0)
			(layer "B.Fab")
			(effects
				(font
					(size 0.7 0.7)
					(thickness 0.15)
				)
				(justify right top mirror)
			)
		)
		(fp_text user "License: Apache-2.0"
			(at -0.95 -5.169 0)
			(layer "B.Fab")
			(effects
				(font
					(size 0.7 0.7)
					(thickness 0.15)
				)
				(justify right top mirror)
			)
		)
		(fp_text user "Author: Antmicro"
			(at -0.95 -4.169 0)
			(layer "B.Fab")
			(effects
				(font
					(size 0.7 0.7)
					(thickness 0.15)
				)
				(justify right top mirror)
			)
		)
		(pad "1" smd roundrect
			(at -0.48 0)
			(size 0.59 0.64)
			(layers "B.Cu" "B.Mask" "B.Paste")
			(roundrect_rratio 0.25)
			(net 1 "GND")
			(pintype "passive")
		)
		(pad "2" smd roundrect
			(at 0.48 0)
			(size 0.59 0.64)
			(layers "B.Cu" "B.Mask" "B.Paste")
			(roundrect_rratio 0.25)
			(net 171 "/SoM_IO2/SFI_REFCLK-")
			(pintype "passive")
		)
	)
	(footprint "antmicro-footprints:TP_SMD_0.75mm"
		(layer "B.Cu")
		(at 165.15 58.02 180)
		(property "Reference" "TP134"
			(at -0.42 4.06 90)
			(layer "B.SilkS")
			(effects
				(font
					(size 0.7 0.7)
					(thickness 0.15)
				)
				(justify left bottom mirror)
			)
		)
		(property "Value" "TP_0.75mm_SMD"
			(at 0 -1.2 0)
			(layer "B.Fab")
			(effects
				(font
					(size 0.7 0.7)
					(thickness 0.15)
				)
				(justify left bottom mirror)
			)
		)
		(property "Description" "SMT test point"
			(at 0 0 0)
			(layer "B.Fab")
			(hide yes)
			(effects
				(font
					(size 1.27 1.27)
					(thickness 0.15)
				)
				(justify mirror)
			)
		)
		(property "MPN" ""
			(at 0 0 0)
			(unlocked yes)
			(layer "B.Fab")
			(hide yes)
			(effects
				(font
					(size 1 1)
					(thickness 0.15)
				)
				(justify mirror)
			)
		)
		(property "Manufacturer" ""
			(at 0 0 0)
			(unlocked yes)
			(layer "B.Fab")
			(hide yes)
			(effects
				(font
					(size 1 1)
					(thickness 0.15)
				)
				(justify mirror)
			)
		)
		(property "Author" "Antmicro"
			(at 0 0 0)
			(unlocked yes)
			(layer "B.Fab")
			(hide yes)
			(effects
				(font
					(size 1 1)
					(thickness 0.15)
				)
				(justify mirror)
			)
		)
		(property "License" "Apache-2.0"
			(at 0 0 0)
			(unlocked yes)
			(layer "B.Fab")
			(hide yes)
			(effects
				(font
					(size 1 1)
					(thickness 0.15)
				)
				(justify mirror)
			)
		)
		(sheetname "/Power/")
		(sheetfile "power.kicad_sch")
		(attr exclude_from_pos_files exclude_from_bom)
		(fp_circle
			(center 0 0)
			(end 0.475 0)
			(stroke
				(width 0.05)
				(type default)
			)
			(fill no)
			(layer "B.CrtYd")
		)
		(fp_text user "${REFERENCE}"
			(at -0.4 -2.7 0)
			(layer "B.Fab")
			(effects
				(font
					(size 0.7 0.7)
					(thickness 0.15)
				)
				(justify left bottom mirror)
			)
		)
		(fp_text user "License: Apache-2.0"
			(at -0.4 -5.101 0)
			(layer "B.Fab")
			(effects
				(font
					(size 0.7 0.7)
					(thickness 0.15)
				)
				(justify left bottom mirror)
			)
		)
		(fp_text user "Author: Antmicro"
			(at -0.4 -3.901 0)
			(layer "B.Fab")
			(effects
				(font
					(size 0.7 0.7)
					(thickness 0.15)
				)
				(justify left bottom mirror)
			)
		)
		(pad "1" smd circle
			(at 0 0 180)
			(size 0.75 0.75)
			(layers "B.Cu" "B.Mask")
			(net 1 "GND")
			(pinfunction "1")
			(pintype "passive")
		)
	)
	(footprint "antmicro-footprints:C_0402_1005Metric"
		(layer "B.Cu")
		(at 214.5 70.65 90)
		(descr "Capacitor SMD 0402")
		(tags "capacitor SMD 0402")
		(property "Reference" "C135"
			(at 0.95 -0.4 90)
			(layer "B.SilkS")
			(effects
				(font
					(size 0.7 0.7)
					(thickness 0.15)
				)
				(justify right top mirror)
			)
		)
		(property "Value" "C_10u_0402"
			(at -1.022927 -2.155213 90)
			(layer "B.Fab")
			(effects
				(font
					(size 0.7 0.7)
					(thickness 0.15)
				)
				(justify right top mirror)
			)
		)
		(property "Datasheet" "https://www.yageo.com/en/Chart/Download/pdf/CC0402MRX5R5BB106"
			(at 0 0 90)
			(layer "B.Fab")
			(hide yes)
			(effects
				(font
					(size 1.27 1.27)
					(thickness 0.15)
				)
				(justify mirror)
			)
		)
		(property "Description" "SMD Multilayer Ceramic Capacitor, 10 µF, 6.3 V, 0402 [1005 Metric], ± 20%, X5R, CC Series"
			(at 0 0 90)
			(layer "B.Fab")
			(hide yes)
			(effects
				(font
					(size 1.27 1.27)
					(thickness 0.15)
				)
				(justify mirror)
			)
		)
		(property "MPN" "CC0402MRX5R5BB106"
			(at 0 0 270)
			(unlocked yes)
			(layer "B.Fab")
			(hide yes)
			(effects
				(font
					(size 1 1)
					(thickness 0.15)
				)
				(justify mirror)
			)
		)
		(property "Manufacturer" "YAGEO"
			(at 0 0 270)
			(unlocked yes)
			(layer "B.Fab")
			(hide yes)
			(effects
				(font
					(size 1 1)
					(thickness 0.15)
				)
				(justify mirror)
			)
		)
		(property "License" "Apache-2.0"
			(at 0 0 270)
			(unlocked yes)
			(layer "B.Fab")
			(hide yes)
			(effects
				(font
					(size 1 1)
					(thickness 0.15)
				)
				(justify mirror)
			)
		)
		(property "Author" "Antmicro"
			(at 0 0 270)
			(unlocked yes)
			(layer "B.Fab")
			(hide yes)
			(effects
				(font
					(size 1 1)
					(thickness 0.15)
				)
				(justify mirror)
			)
		)
		(property "Val" "10u"
			(at 0 0 270)
			(unlocked yes)
			(layer "B.Fab")
			(hide yes)
			(effects
				(font
					(size 1 1)
					(thickness 0.15)
				)
				(justify mirror)
			)
		)
		(property "Voltage" ""
			(at 0 0 270)
			(unlocked yes)
			(layer "B.Fab")
			(hide yes)
			(effects
				(font
					(size 1 1)
					(thickness 0.15)
				)
				(justify mirror)
			)
		)
		(property "Dielectric" ""
			(at 0 0 270)
			(unlocked yes)
			(layer "B.Fab")
			(hide yes)
			(effects
				(font
					(size 1 1)
					(thickness 0.15)
				)
				(justify mirror)
			)
		)
		(sheetname "/USB Debug, PD/")
		(sheetfile "usb_debug_pd.kicad_sch")
		(attr smd)
		(fp_rect
			(start -0.925 0.47)
			(end 0.925 -0.47)
			(stroke
				(width 0.05)
				(type default)
			)
			(fill no)
			(layer "B.CrtYd")
		)
		(fp_line
			(start 0.504 -0.248)
			(end -0.494 -0.248)
			(stroke
				(width 0.15)
				(type solid)
			)
			(layer "B.Fab")
		)
		(fp_line
			(start -0.494 -0.248)
			(end -0.494 0.25)
			(stroke
				(width 0.15)
				(type solid)
			)
			(layer "B.Fab")
		)
		(fp_line
			(start 0.504 0.25)
			(end 0.504 -0.248)
			(stroke
				(width 0.15)
				(type solid)
			)
			(layer "B.Fab")
		)
		(fp_line
			(start -0.494 0.25)
			(end 0.504 0.25)
			(stroke
				(width 0.15)
				(type solid)
			)
			(layer "B.Fab")
		)
		(fp_text user "License: Apache-2.0"
			(at -0.939 -5.799 90)
			(layer "B.Fab")
			(effects
				(font
					(size 0.7 0.7)
					(thickness 0.15)
				)
				(justify right top mirror)
			)
		)
		(fp_text user "${REFERENCE}"
			(at -0.939 -4.599 90)
			(layer "B.Fab")
			(effects
				(font
					(size 0.7 0.7)
					(thickness 0.15)
				)
				(justify right top mirror)
			)
		)
		(fp_text user "Author: Antmicro"
			(at -0.939 -3.399 90)
			(layer "B.Fab")
			(effects
				(font
					(size 0.7 0.7)
					(thickness 0.15)
				)
				(justify right top mirror)
			)
		)
		(pad "1" smd roundrect
			(at -0.48 0 90)
			(size 0.59 0.64)
			(layers "B.Cu" "B.Mask" "B.Paste")
			(roundrect_rratio 0.25)
			(net 1 "GND")
			(pintype "passive")
		)
		(pad "2" smd roundrect
			(at 0.48 0 90)
			(size 0.59 0.64)
			(layers "B.Cu" "B.Mask" "B.Paste")
			(roundrect_rratio 0.25)
			(net 334 "/USB Debug, PD/FTDI_3V3")
			(pintype "passive")
		)
	)
	(footprint "antmicro-footprints:R_0402_1005Metric"
		(layer "B.Cu")
		(at 200.8 124.2 180)
		(descr "Resistor SMD 0402")
		(tags "resistor SMD 0402")
		(property "Reference" "R325"
			(at -3.8 -0.4 0)
			(layer "B.SilkS")
			(effects
				(font
					(size 0.7 0.7)
					(thickness 0.15)
				)
				(justify left bottom mirror)
			)
		)
		(property "Value" "R_100k_0402"
			(at -1.011843 -1.772046 0)
			(layer "B.Fab")
			(effects
				(font
					(size 0.7 0.7)
					(thickness 0.15)
				)
				(justify left bottom mirror)
			)
		)
		(property "Datasheet" "https://www.bourns.com/docs/product-datasheets/cr.pdf"
			(at 0 0 0)
			(layer "B.Fab")
			(hide yes)
			(effects
				(font
					(size 1.27 1.27)
					(thickness 0.15)
				)
				(justify mirror)
			)
		)
		(property "Description" "SMD Chip Resistor, 100 kohm, ± 1%, 62.5 mW, 0402 [1005 Metric], Thick Film, General Purpose"
			(at 0 0 0)
			(layer "B.Fab")
			(hide yes)
			(effects
				(font
					(size 1.27 1.27)
					(thickness 0.15)
				)
				(justify mirror)
			)
		)
		(property "MPN" "CR0402-FX-1003GLF"
			(at 0 0 0)
			(unlocked yes)
			(layer "B.Fab")
			(hide yes)
			(effects
				(font
					(size 1 1)
					(thickness 0.15)
				)
				(justify mirror)
			)
		)
		(property "Manufacturer" "Bourns"
			(at 0 0 0)
			(unlocked yes)
			(layer "B.Fab")
			(hide yes)
			(effects
				(font
					(size 1 1)
					(thickness 0.15)
				)
				(justify mirror)
			)
		)
		(property "License" "Apache-2.0"
			(at 0 0 0)
			(unlocked yes)
			(layer "B.Fab")
			(hide yes)
			(effects
				(font
					(size 1 1)
					(thickness 0.15)
				)
				(justify mirror)
			)
		)
		(property "Author" "Antmicro"
			(at 0 0 0)
			(unlocked yes)
			(layer "B.Fab")
			(hide yes)
			(effects
				(font
					(size 1 1)
					(thickness 0.15)
				)
				(justify mirror)
			)
		)
		(property "Val" "100k"
			(at 0 0 0)
			(unlocked yes)
			(layer "B.Fab")
			(hide yes)
			(effects
				(font
					(size 1 1)
					(thickness 0.15)
				)
				(justify mirror)
			)
		)
		(property "Tolerance" "1%"
			(at 0 0 0)
			(unlocked yes)
			(layer "B.Fab")
			(hide yes)
			(effects
				(font
					(size 1 1)
					(thickness 0.15)
				)
				(justify mirror)
			)
		)
		(sheetname "/USB Hub/")
		(sheetfile "usb_hub.kicad_sch")
		(attr smd)
		(fp_poly
			(pts
				(xy -0.925 0.47) (xy -0.925 -0.47) (xy 0.925 -0.47) (xy 0.925 0.47)
			)
			(stroke
				(width 0.05)
				(type default)
			)
			(fill no)
			(layer "B.CrtYd")
		)
		(fp_poly
			(pts
				(xy -0.5 0.25) (xy -0.5 -0.25) (xy 0.5 -0.25) (xy 0.5 0.25)
			)
			(stroke
				(width 0.15)
				(type solid)
			)
			(fill no)
			(layer "B.Fab")
		)
		(fp_text user "License: Apache-2.0"
			(at -0.949999 -5.169 0)
			(layer "B.Fab")
			(effects
				(font
					(size 0.7 0.7)
					(thickness 0.15)
				)
				(justify left bottom mirror)
			)
		)
		(fp_text user "Author: Antmicro"
			(at -0.95 -4.169 0)
			(layer "B.Fab")
			(effects
				(font
					(size 0.7 0.7)
					(thickness 0.15)
				)
				(justify left bottom mirror)
			)
		)
		(fp_text user "${REFERENCE}"
			(at -0.95 -3.168 0)
			(layer "B.Fab")
			(effects
				(font
					(size 0.7 0.7)
					(thickness 0.15)
				)
				(justify left bottom mirror)
			)
		)
		(pad "1" smd roundrect
			(at -0.48 0 180)
			(size 0.59 0.64)
			(layers "B.Cu" "B.Mask" "B.Paste")
			(roundrect_rratio 0.25)
			(net 1 "GND")
			(pintype "passive")
		)
		(pad "2" smd roundrect
			(at 0.48 0 180)
			(size 0.59 0.64)
			(layers "B.Cu" "B.Mask" "B.Paste")
			(roundrect_rratio 0.25)
			(net 927 "/USB Hub/HUB_SPI_CLK")
			(pintype "passive")
		)
	)
)
